(kicad_pcb
	(version 20260206)
	(generator "pcbnew")
	(generator_version "10.0")
	(general
		(thickness 1.6)
		(legacy_teardrops no)
	)
	(paper "A4")
	(title_block
		(title "dpb — 14545-sa.0730WZS0815.brd")
		(comment 1 "Honey Badger (Wiwynn) / footprints 416-422 of 1066")
	)
	(layers
		(0 "F.Cu" signal "TOP")
		(4 "In1.Cu" signal "L2GND")
		(6 "In2.Cu" signal "L3")
		(8 "In3.Cu" signal "L4VCC")
		(10 "In4.Cu" signal "L5VCC")
		(12 "In5.Cu" signal "L6")
		(14 "In6.Cu" signal "L7GND")
		(2 "B.Cu" signal "BOTTOM")
		(9 "F.Adhes" user "F.Adhesive")
		(11 "B.Adhes" user "B.Adhesive")
		(13 "F.Paste" user "Package Geometry/Pastemask Top")
		(15 "B.Paste" user "Package Geometry/Pastemask Bottom")
		(5 "F.SilkS" user "Ref Des/Silkscreen Top")
		(7 "B.SilkS" user "Ref Des/Silkscreen Bottom")
		(1 "F.Mask" user "Board Geometry/Soldermask Top")
		(3 "B.Mask" user "Board Geometry/Soldermask Bottom")
		(17 "Dwgs.User" user "User.Drawings")
		(19 "Cmts.User" user "User.Comments")
		(21 "Eco1.User" user "User.Eco1")
		(23 "Eco2.User" user "User.Eco2")
		(25 "Edge.Cuts" user "Board Geometry/Outline")
		(27 "Margin" user)
		(31 "F.CrtYd" user "Package Geometry/Place Bound Top")
		(29 "B.CrtYd" user "Package Geometry/Place Bound Bottom")
		(35 "F.Fab" user "Ref Des/Assembly Top")
		(33 "B.Fab" user "Ref Des/Assembly Bottom")
	)
	(footprint ""
		(layer "F.Cu")
		(at 210.312 -478.282 180)
		(property "Reference" "R342"
			(at 0 0 180)
			(layer "F.SilkS")
			(hide yes)
			(effects
				(font
					(size 1.27 1.27)
				)
			)
		)
		(property "Value" "10KR2F-2-GP"
			(at 0.064008 -3.993896 180)
			(unlocked yes)
			(layer "F.Fab")
			(hide yes)
			(effects
				(font
					(size 1.016 1.016)
					(thickness 0.1524)
				)
			)
		)
		(property "Device Type" "R402H16"
			(at 0.064008 -5.517896 180)
			(unlocked yes)
			(layer "F.Fab")
			(hide yes)
			(effects
				(font
					(size 1.016 1.016)
					(thickness 0.1524)
				)
			)
		)
		(duplicate_pad_numbers_are_jumpers no)
		(fp_line
			(start 0.508 -0.9398)
			(end -0.508 -0.9398)
			(stroke
				(width 0.1524)
				(type default)
			)
			(layer "F.SilkS")
		)
		(fp_line
			(start -0.508 -0.9398)
			(end -0.508 0.9398)
			(stroke
				(width 0.1524)
				(type default)
			)
			(layer "F.SilkS")
		)
		(fp_rect
			(start -0.508 0.9398)
			(end 0.508 -0.9398)
			(stroke
				(width 0)
				(type default)
			)
			(fill no)
			(layer "F.CrtYd")
		)
		(fp_rect
			(start -0.508 0.9398)
			(end 0.508 -0.9398)
			(stroke
				(width 0)
				(type default)
			)
			(fill no)
			(layer "F.Fab")
		)
		(pad "1" smd custom
			(at 0 -0.4445 180)
			(size 0.1397 0.1397)
			(layers "F.Cu" "F.Mask" "F.Paste")
			(net "P12V")
			(options
				(clearance outline)
				(anchor circle)
			)
			(primitives
				(gr_poly
					(pts
						(arc
							(start -0.1778 -0.2794)
							(mid -0.249642 -0.249642)
							(end -0.2794 -0.1778)
						)
						(arc
							(start -0.2794 0.1778)
							(mid -0.249642 0.249642)
							(end -0.1778 0.2794)
						)
						(arc
							(start 0.1778 0.2794)
							(mid 0.249642 0.249642)
							(end 0.2794 0.1778)
						)
						(arc
							(start 0.2794 -0.1778)
							(mid 0.249642 -0.249642)
							(end 0.1778 -0.2794)
						)
					)
					(width 0)
					(fill yes)
				)
			)
		)
		(pad "2" smd custom
			(at 0 0.4445 180)
			(size 0.1397 0.1397)
			(layers "F.Cu" "F.Mask" "F.Paste")
			(net "HDD0_LED_G")
			(options
				(clearance outline)
				(anchor circle)
			)
			(primitives
				(gr_poly
					(pts
						(arc
							(start -0.1778 -0.2794)
							(mid -0.249642 -0.249642)
							(end -0.2794 -0.1778)
						)
						(arc
							(start -0.2794 0.1778)
							(mid -0.249642 0.249642)
							(end -0.1778 0.2794)
						)
						(arc
							(start 0.1778 0.2794)
							(mid 0.249642 0.249642)
							(end 0.2794 0.1778)
						)
						(arc
							(start 0.2794 -0.1778)
							(mid 0.249642 -0.249642)
							(end 0.1778 -0.2794)
						)
					)
					(width 0)
					(fill yes)
				)
			)
		)
	)
	(footprint ""
		(layer "F.Cu")
		(at 191.897 -89.281 90)
		(property "Reference" "R165"
			(at 0 0 90)
			(layer "F.SilkS")
			(hide yes)
			(effects
				(font
					(size 1.27 1.27)
				)
			)
		)
		(property "Value" "4K7R2J-2-GP"
			(at 0.064008 -3.993896 90)
			(unlocked yes)
			(layer "F.Fab")
			(hide yes)
			(effects
				(font
					(size 1.016 1.016)
					(thickness 0.1524)
				)
			)
		)
		(property "Device Type" "R402H16"
			(at 0.064008 -5.517896 90)
			(unlocked yes)
			(layer "F.Fab")
			(hide yes)
			(effects
				(font
					(size 1.016 1.016)
					(thickness 0.1524)
				)
			)
		)
		(duplicate_pad_numbers_are_jumpers no)
		(fp_line
			(start 0.508 -0.9398)
			(end -0.508 -0.9398)
			(stroke
				(width 0.1524)
				(type default)
			)
			(layer "F.SilkS")
		)
		(fp_line
			(start -0.508 -0.9398)
			(end -0.508 0.9398)
			(stroke
				(width 0.1524)
				(type default)
			)
			(layer "F.SilkS")
		)
		(fp_rect
			(start -0.508 0.9398)
			(end 0.508 -0.9398)
			(stroke
				(width 0)
				(type default)
			)
			(fill no)
			(layer "F.CrtYd")
		)
		(fp_rect
			(start -0.508 0.9398)
			(end 0.508 -0.9398)
			(stroke
				(width 0)
				(type default)
			)
			(fill no)
			(layer "F.Fab")
		)
		(pad "1" smd custom
			(at 0 -0.4445 90)
			(size 0.1397 0.1397)
			(layers "F.Cu" "F.Mask" "F.Paste")
			(net "P12V")
			(options
				(clearance outline)
				(anchor circle)
			)
			(primitives
				(gr_poly
					(pts
						(arc
							(start -0.1778 -0.2794)
							(mid -0.249642 -0.249642)
							(end -0.2794 -0.1778)
						)
						(arc
							(start -0.2794 0.1778)
							(mid -0.249642 0.249642)
							(end -0.1778 0.2794)
						)
						(arc
							(start 0.1778 0.2794)
							(mid 0.249642 0.249642)
							(end 0.2794 0.1778)
						)
						(arc
							(start 0.2794 -0.1778)
							(mid 0.249642 -0.249642)
							(end 0.1778 -0.2794)
						)
					)
					(width 0)
					(fill yes)
				)
			)
		)
		(pad "2" smd custom
			(at 0 0.4445 90)
			(size 0.1397 0.1397)
			(layers "F.Cu" "F.Mask" "F.Paste")
			(net "SW_HDD4_R")
			(options
				(clearance outline)
				(anchor circle)
			)
			(primitives
				(gr_poly
					(pts
						(arc
							(start -0.1778 -0.2794)
							(mid -0.249642 -0.249642)
							(end -0.2794 -0.1778)
						)
						(arc
							(start -0.2794 0.1778)
							(mid -0.249642 0.249642)
							(end -0.1778 0.2794)
						)
						(arc
							(start 0.1778 0.2794)
							(mid 0.249642 0.249642)
							(end 0.2794 0.1778)
						)
						(arc
							(start 0.2794 -0.1778)
							(mid 0.249642 -0.249642)
							(end 0.1778 -0.2794)
						)
					)
					(width 0)
					(fill yes)
				)
			)
		)
	)
	(footprint ""
		(layer "F.Cu")
		(at 28.447746 -311.305702 180)
		(property "Reference" "R267"
			(at 0 0 180)
			(layer "F.SilkS")
			(hide yes)
			(effects
				(font
					(size 1.27 1.27)
				)
			)
		)
		(property "Value" "0R2J-2-GP"
			(at 0.064008 -3.993896 180)
			(unlocked yes)
			(layer "F.Fab")
			(hide yes)
			(effects
				(font
					(size 1.016 1.016)
					(thickness 0.1524)
				)
			)
		)
		(property "Device Type" "R402H16"
			(at 0.064008 -5.517896 180)
			(unlocked yes)
			(layer "F.Fab")
			(hide yes)
			(effects
				(font
					(size 1.016 1.016)
					(thickness 0.1524)
				)
			)
		)
		(duplicate_pad_numbers_are_jumpers no)
		(fp_line
			(start 0.508 -0.9398)
			(end -0.508 -0.9398)
			(stroke
				(width 0.1524)
				(type default)
			)
			(layer "F.SilkS")
		)
		(fp_line
			(start -0.508 -0.9398)
			(end -0.508 0.9398)
			(stroke
				(width 0.1524)
				(type default)
			)
			(layer "F.SilkS")
		)
		(fp_rect
			(start -0.508 0.9398)
			(end 0.508 -0.9398)
			(stroke
				(width 0)
				(type default)
			)
			(fill no)
			(layer "F.CrtYd")
		)
		(fp_rect
			(start -0.508 0.9398)
			(end 0.508 -0.9398)
			(stroke
				(width 0)
				(type default)
			)
			(fill no)
			(layer "F.Fab")
		)
		(pad "1" smd custom
			(at 0 -0.4445 180)
			(size 0.1397 0.1397)
			(layers "F.Cu" "F.Mask" "F.Paste")
			(net "DRIVE_PWR11")
			(options
				(clearance outline)
				(anchor circle)
			)
			(primitives
				(gr_poly
					(pts
						(arc
							(start -0.1778 -0.2794)
							(mid -0.249642 -0.249642)
							(end -0.2794 -0.1778)
						)
						(arc
							(start -0.2794 0.1778)
							(mid -0.249642 0.249642)
							(end -0.1778 0.2794)
						)
						(arc
							(start 0.1778 0.2794)
							(mid 0.249642 0.249642)
							(end 0.2794 0.1778)
						)
						(arc
							(start 0.2794 -0.1778)
							(mid 0.249642 -0.249642)
							(end 0.1778 -0.2794)
						)
					)
					(width 0)
					(fill yes)
				)
			)
		)
		(pad "2" smd custom
			(at 0 0.4445 180)
			(size 0.1397 0.1397)
			(layers "F.Cu" "F.Mask" "F.Paste")
			(net "SW_PWR_HDD11")
			(options
				(clearance outline)
				(anchor circle)
			)
			(primitives
				(gr_poly
					(pts
						(arc
							(start -0.1778 -0.2794)
							(mid -0.249642 -0.249642)
							(end -0.2794 -0.1778)
						)
						(arc
							(start -0.2794 0.1778)
							(mid -0.249642 0.249642)
							(end -0.1778 0.2794)
						)
						(arc
							(start 0.1778 0.2794)
							(mid 0.249642 0.249642)
							(end 0.2794 0.1778)
						)
						(arc
							(start 0.2794 -0.1778)
							(mid 0.249642 -0.249642)
							(end 0.1778 -0.2794)
						)
					)
					(width 0)
					(fill yes)
				)
			)
		)
	)
	(footprint ""
		(layer "F.Cu")
		(at 101.599746 -10.4267)
		(property "Reference" "R308"
			(at 0 0 0)
			(layer "F.SilkS")
			(hide yes)
			(effects
				(font
					(size 1.27 1.27)
				)
			)
		)
		(property "Value" "0R2J-2-GP"
			(at 0.064008 -3.993896 0)
			(unlocked yes)
			(layer "F.Fab")
			(hide yes)
			(effects
				(font
					(size 1.016 1.016)
					(thickness 0.1524)
				)
			)
		)
		(property "Device Type" "R402H16"
			(at 0.064008 -5.517896 0)
			(unlocked yes)
			(layer "F.Fab")
			(hide yes)
			(effects
				(font
					(size 1.016 1.016)
					(thickness 0.1524)
				)
			)
		)
		(duplicate_pad_numbers_are_jumpers no)
		(fp_line
			(start -0.508 -0.9398)
			(end -0.508 0.9398)
			(stroke
				(width 0.1524)
				(type default)
			)
			(layer "F.SilkS")
		)
		(fp_line
			(start 0.508 -0.9398)
			(end -0.508 -0.9398)
			(stroke
				(width 0.1524)
				(type default)
			)
			(layer "F.SilkS")
		)
		(fp_rect
			(start -0.508 0.9398)
			(end 0.508 -0.9398)
			(stroke
				(width 0)
				(type default)
			)
			(fill no)
			(layer "F.CrtYd")
		)
		(fp_rect
			(start -0.508 0.9398)
			(end 0.508 -0.9398)
			(stroke
				(width 0)
				(type default)
			)
			(fill no)
			(layer "F.Fab")
		)
		(pad "1" smd custom
			(at 0 -0.4445)
			(size 0.1397 0.1397)
			(layers "F.Cu" "F.Mask" "F.Paste")
			(net "SW_PWR_HDD14")
			(options
				(clearance outline)
				(anchor circle)
			)
			(primitives
				(gr_poly
					(pts
						(arc
							(start -0.1778 -0.2794)
							(mid -0.249642 -0.249642)
							(end -0.2794 -0.1778)
						)
						(arc
							(start -0.2794 0.1778)
							(mid -0.249642 0.249642)
							(end -0.1778 0.2794)
						)
						(arc
							(start 0.1778 0.2794)
							(mid 0.249642 0.249642)
							(end 0.2794 0.1778)
						)
						(arc
							(start 0.2794 -0.1778)
							(mid 0.249642 -0.249642)
							(end 0.1778 -0.2794)
						)
					)
					(width 0)
					(fill yes)
				)
			)
		)
		(pad "2" smd custom
			(at 0 0.4445)
			(size 0.1397 0.1397)
			(layers "F.Cu" "F.Mask" "F.Paste")
			(net "SW_PWR_R_HDD14")
			(options
				(clearance outline)
				(anchor circle)
			)
			(primitives
				(gr_poly
					(pts
						(arc
							(start -0.1778 -0.2794)
							(mid -0.249642 -0.249642)
							(end -0.2794 -0.1778)
						)
						(arc
							(start -0.2794 0.1778)
							(mid -0.249642 0.249642)
							(end -0.1778 0.2794)
						)
						(arc
							(start 0.1778 0.2794)
							(mid 0.249642 0.249642)
							(end 0.2794 0.1778)
						)
						(arc
							(start 0.2794 -0.1778)
							(mid 0.249642 -0.249642)
							(end 0.1778 -0.2794)
						)
					)
					(width 0)
					(fill yes)
				)
			)
		)
	)
	(footprint ""
		(layer "F.Cu")
		(at 46.202346 -126.5301)
		(property "Reference" "R505"
			(at 0 0 0)
			(layer "F.SilkS")
			(hide yes)
			(effects
				(font
					(size 1.27 1.27)
				)
			)
		)
		(property "Value" "4K7R2J-2-GP"
			(at 0.064008 -3.993896 0)
			(unlocked yes)
			(layer "F.Fab")
			(hide yes)
			(effects
				(font
					(size 1.016 1.016)
					(thickness 0.1524)
				)
			)
		)
		(property "Device Type" "R402H16"
			(at 0.064008 -5.517896 0)
			(unlocked yes)
			(layer "F.Fab")
			(hide yes)
			(effects
				(font
					(size 1.016 1.016)
					(thickness 0.1524)
				)
			)
		)
		(duplicate_pad_numbers_are_jumpers no)
		(fp_line
			(start -0.508 -0.9398)
			(end -0.508 0.9398)
			(stroke
				(width 0.1524)
				(type default)
			)
			(layer "F.SilkS")
		)
		(fp_line
			(start 0.508 -0.9398)
			(end -0.508 -0.9398)
			(stroke
				(width 0.1524)
				(type default)
			)
			(layer "F.SilkS")
		)
		(fp_rect
			(start -0.508 0.9398)
			(end 0.508 -0.9398)
			(stroke
				(width 0)
				(type default)
			)
			(fill no)
			(layer "F.CrtYd")
		)
		(fp_rect
			(start -0.508 0.9398)
			(end 0.508 -0.9398)
			(stroke
				(width 0)
				(type default)
			)
			(fill no)
			(layer "F.Fab")
		)
		(pad "1" smd custom
			(at 0 -0.4445)
			(size 0.1397 0.1397)
			(layers "F.Cu" "F.Mask" "F.Paste")
			(net "P3V3")
			(options
				(clearance outline)
				(anchor circle)
			)
			(primitives
				(gr_poly
					(pts
						(arc
							(start -0.1778 -0.2794)
							(mid -0.249642 -0.249642)
							(end -0.2794 -0.1778)
						)
						(arc
							(start -0.2794 0.1778)
							(mid -0.249642 0.249642)
							(end -0.1778 0.2794)
						)
						(arc
							(start 0.1778 0.2794)
							(mid 0.249642 0.249642)
							(end 0.2794 0.1778)
						)
						(arc
							(start 0.2794 -0.1778)
							(mid 0.249642 -0.249642)
							(end 0.1778 -0.2794)
						)
					)
					(width 0)
					(fill yes)
				)
			)
		)
		(pad "2" smd custom
			(at 0 0.4445)
			(size 0.1397 0.1397)
			(layers "F.Cu" "F.Mask" "F.Paste")
			(net "SAS2X28_A_HDD13_FLT")
			(options
				(clearance outline)
				(anchor circle)
			)
			(primitives
				(gr_poly
					(pts
						(arc
							(start -0.1778 -0.2794)
							(mid -0.249642 -0.249642)
							(end -0.2794 -0.1778)
						)
						(arc
							(start -0.2794 0.1778)
							(mid -0.249642 0.249642)
							(end -0.1778 0.2794)
						)
						(arc
							(start 0.1778 0.2794)
							(mid 0.249642 0.249642)
							(end 0.2794 0.1778)
						)
						(arc
							(start 0.2794 -0.1778)
							(mid 0.249642 -0.249642)
							(end 0.1778 -0.2794)
						)
					)
					(width 0)
					(fill yes)
				)
			)
		)
	)
	(footprint ""
		(layer "F.Cu")
		(at 77.977746 -87.2617 90)
		(property "Reference" "R238"
			(at 0 0 90)
			(layer "F.SilkS")
			(hide yes)
			(effects
				(font
					(size 1.27 1.27)
				)
			)
		)
		(property "Value" "0R2J-2-GP"
			(at 0.064008 -3.993896 90)
			(unlocked yes)
			(layer "F.Fab")
			(hide yes)
			(effects
				(font
					(size 1.016 1.016)
					(thickness 0.1524)
				)
			)
		)
		(property "Device Type" "R402H16"
			(at 0.064008 -5.517896 90)
			(unlocked yes)
			(layer "F.Fab")
			(hide yes)
			(effects
				(font
					(size 1.016 1.016)
					(thickness 0.1524)
				)
			)
		)
		(duplicate_pad_numbers_are_jumpers no)
		(fp_line
			(start 0.508 -0.9398)
			(end -0.508 -0.9398)
			(stroke
				(width 0.1524)
				(type default)
			)
			(layer "F.SilkS")
		)
		(fp_line
			(start -0.508 -0.9398)
			(end -0.508 0.9398)
			(stroke
				(width 0.1524)
				(type default)
			)
			(layer "F.SilkS")
		)
		(fp_rect
			(start -0.508 0.9398)
			(end 0.508 -0.9398)
			(stroke
				(width 0)
				(type default)
			)
			(fill no)
			(layer "F.CrtYd")
		)
		(fp_rect
			(start -0.508 0.9398)
			(end 0.508 -0.9398)
			(stroke
				(width 0)
				(type default)
			)
			(fill no)
			(layer "F.Fab")
		)
		(pad "1" smd custom
			(at 0 -0.4445 90)
			(size 0.1397 0.1397)
			(layers "F.Cu" "F.Mask" "F.Paste")
			(net "SW_PWR_HDD9")
			(options
				(clearance outline)
				(anchor circle)
			)
			(primitives
				(gr_poly
					(pts
						(arc
							(start -0.1778 -0.2794)
							(mid -0.249642 -0.249642)
							(end -0.2794 -0.1778)
						)
						(arc
							(start -0.2794 0.1778)
							(mid -0.249642 0.249642)
							(end -0.1778 0.2794)
						)
						(arc
							(start 0.1778 0.2794)
							(mid 0.249642 0.249642)
							(end 0.2794 0.1778)
						)
						(arc
							(start 0.2794 -0.1778)
							(mid 0.249642 -0.249642)
							(end 0.1778 -0.2794)
						)
					)
					(width 0)
					(fill yes)
				)
			)
		)
		(pad "2" smd custom
			(at 0 0.4445 90)
			(size 0.1397 0.1397)
			(layers "F.Cu" "F.Mask" "F.Paste")
			(net "SW_PWR_R_HDD9")
			(options
				(clearance outline)
				(anchor circle)
			)
			(primitives
				(gr_poly
					(pts
						(arc
							(start -0.1778 -0.2794)
							(mid -0.249642 -0.249642)
							(end -0.2794 -0.1778)
						)
						(arc
							(start -0.2794 0.1778)
							(mid -0.249642 0.249642)
							(end -0.1778 0.2794)
						)
						(arc
							(start 0.1778 0.2794)
							(mid 0.249642 0.249642)
							(end 0.2794 0.1778)
						)
						(arc
							(start 0.2794 -0.1778)
							(mid 0.249642 -0.249642)
							(end 0.1778 -0.2794)
						)
					)
					(width 0)
					(fill yes)
				)
			)
		)
	)
	(footprint ""
		(layer "F.Cu")
		(at 27.177746 -32.0167 90)
		(property "Reference" "C329"
			(at 0 0 90)
			(layer "F.SilkS")
			(hide yes)
			(effects
				(font
					(size 1.27 1.27)
				)
			)
		)
		(property "Value" "SCD01U50V2KX-1GP"
			(at 1.1811 -2.7051 90)
			(unlocked yes)
			(layer "F.Fab")
			(hide yes)
			(effects
				(font
					(size 1.016 1.016)
					(thickness 0.1524)
				)
			)
		)
		(property "Device Type" "C402H22"
			(at 1.1811 -4.2291 90)
			(unlocked yes)
			(layer "F.Fab")
			(hide yes)
			(effects
				(font
					(size 1.016 1.016)
					(thickness 0.1524)
				)
			)
		)
		(duplicate_pad_numbers_are_jumpers no)
		(fp_rect
			(start -0.4318 0.9525)
			(end 0.4318 -0.9525)
			(stroke
				(width 0)
				(type default)
			)
			(fill no)
			(layer "F.CrtYd")
		)
		(fp_rect
			(start -0.4318 0.9525)
			(end 0.4318 -0.9525)
			(stroke
				(width 0)
				(type default)
			)
			(fill no)
			(layer "F.Fab")
		)
		(pad "1" smd custom
			(at 0 -0.4445 90)
			(size 0.1524 0.1524)
			(layers "F.Cu" "F.Mask" "F.Paste")
			(net "SAS2X28_DRIVE_RX_P_B14")
			(options
				(clearance outline)
				(anchor circle)
			)
			(primitives
				(gr_poly
					(pts
						(arc
							(start 0.3048 -0.2032)
							(mid 0.275042 -0.275042)
							(end 0.2032 -0.3048)
						)
						(arc
							(start -0.2032 -0.3048)
							(mid -0.275042 -0.275042)
							(end -0.3048 -0.2032)
						)
						(arc
							(start -0.3048 0.2032)
							(mid -0.275042 0.275042)
							(end -0.2032 0.3048)
						)
						(arc
							(start 0.2032 0.3048)
							(mid 0.275042 0.275042)
							(end 0.3048 0.2032)
						)
					)
					(width 0)
					(fill yes)
				)
			)
		)
		(pad "2" smd custom
			(at 0 0.4445 90)
			(size 0.1524 0.1524)
			(layers "F.Cu" "F.Mask" "F.Paste")
			(net "SAS2X28_B_HDD14_RX_+")
			(options
				(clearance outline)
				(anchor circle)
			)
			(primitives
				(gr_poly
					(pts
						(arc
							(start 0.3048 -0.2032)
							(mid 0.275042 -0.275042)
							(end 0.2032 -0.3048)
						)
						(arc
							(start -0.2032 -0.3048)
							(mid -0.275042 -0.275042)
							(end -0.3048 -0.2032)
						)
						(arc
							(start -0.3048 0.2032)
							(mid -0.275042 0.275042)
							(end -0.2032 0.3048)
						)
						(arc
							(start 0.2032 0.3048)
							(mid 0.275042 0.275042)
							(end 0.3048 0.2032)
						)
					)
					(width 0)
					(fill yes)
				)
			)
		)
	)
)
